(kicad_pcb
	(version 20260206)
	(generator "pcbnew")
	(generator_version "10.0")
	(general
		(thickness 1.6)
		(legacy_teardrops no)
	)
	(paper "A4")
	(title_block
		(title "03242023_DA0F0TMBIJ0_F0T_Motherboard_J_brd_V01_OCP.brd")
		(comment 1 "Grand Teton / footprints 964-970 of 6105")
	)
	(layers
		(0 "F.Cu" signal "TOP")
		(4 "In1.Cu" signal "GND")
		(6 "In2.Cu" signal "IN1")
		(8 "In3.Cu" signal "GND1")
		(10 "In4.Cu" signal "IN2")
		(12 "In5.Cu" signal "GND2")
		(14 "In6.Cu" signal "IN3")
		(16 "In7.Cu" signal "GND3")
		(18 "In8.Cu" signal "VCC")
		(20 "In9.Cu" signal "VCC1")
		(22 "In10.Cu" signal "GND4")
		(24 "In11.Cu" signal "IN4")
		(26 "In12.Cu" signal "GND5")
		(28 "In13.Cu" signal "IN5")
		(30 "In14.Cu" signal "GND6")
		(32 "In15.Cu" signal "IN6")
		(34 "In16.Cu" signal "GND7")
		(2 "B.Cu" signal "BOTTOM")
		(9 "F.Adhes" user "F.Adhesive")
		(11 "B.Adhes" user "B.Adhesive")
		(13 "F.Paste" user "Package Geometry/Pastemask Top")
		(15 "B.Paste" user "Package Geometry/Pastemask Bottom")
		(5 "F.SilkS" user "Ref Des/Silkscreen Top")
		(7 "B.SilkS" user "Ref Des/Silkscreen Bottom")
		(1 "F.Mask" user "Board Geometry/Soldermask Top")
		(3 "B.Mask" user "Board Geometry/Soldermask Bottom")
		(17 "Dwgs.User" user "User.Drawings")
		(19 "Cmts.User" user "User.Comments")
		(21 "Eco1.User" user "User.Eco1")
		(23 "Eco2.User" user "User.Eco2")
		(25 "Edge.Cuts" user "Board Geometry/Outline")
		(27 "Margin" user)
		(31 "F.CrtYd" user "Package Geometry/Place Bound Top")
		(29 "B.CrtYd" user "Package Geometry/Place Bound Bottom")
		(35 "F.Fab" user "Ref Des/Assembly Top")
		(33 "B.Fab" user "Ref Des/Assembly Bottom")
	)
	(footprint ""
		(layer "F.Cu")
		(at 353.851972 -353.137724)
		(property "Reference" "PC331"
			(at 0 0 0)
			(layer "F.SilkS")
			(hide yes)
			(effects
				(font
					(size 1.27 1.27)
				)
			)
		)
		(property "Value" ""
			(at 0 0 0)
			(layer "F.Fab")
			(effects
				(font
					(size 1.27 1.27)
				)
			)
		)
		(duplicate_pad_numbers_are_jumpers no)
		(fp_line
			(start -0.7874 -0.4064)
			(end 0.7874 -0.4064)
			(stroke
				(width 0.1524)
				(type default)
			)
			(layer "F.SilkS")
		)
		(fp_line
			(start -0.7874 0.4064)
			(end -0.7874 -0.4064)
			(stroke
				(width 0.1524)
				(type default)
			)
			(layer "F.SilkS")
		)
		(fp_line
			(start 0.7874 -0.4064)
			(end 0.7874 0.4064)
			(stroke
				(width 0.1524)
				(type default)
			)
			(layer "F.SilkS")
		)
		(fp_line
			(start 0.7874 0.4064)
			(end -0.7874 0.4064)
			(stroke
				(width 0.1524)
				(type default)
			)
			(layer "F.SilkS")
		)
		(fp_line
			(start -0.67945 -0.305054)
			(end -0.12065 -0.305054)
			(stroke
				(width 0.1)
				(type default)
			)
			(layer "F.Fab")
		)
		(fp_line
			(start -0.67945 0.3048)
			(end -0.67945 -0.305054)
			(stroke
				(width 0.1)
				(type default)
			)
			(layer "F.Fab")
		)
		(fp_line
			(start -0.12065 -0.305054)
			(end -0.12065 -0.2794)
			(stroke
				(width 0.1)
				(type default)
			)
			(layer "F.Fab")
		)
		(fp_line
			(start -0.12065 -0.2794)
			(end 0.12065 -0.2794)
			(stroke
				(width 0.1)
				(type default)
			)
			(layer "F.Fab")
		)
		(fp_line
			(start -0.12065 0.2794)
			(end -0.12065 0.3048)
			(stroke
				(width 0.1)
				(type default)
			)
			(layer "F.Fab")
		)
		(fp_line
			(start -0.12065 0.3048)
			(end -0.67945 0.3048)
			(stroke
				(width 0.1)
				(type default)
			)
			(layer "F.Fab")
		)
		(fp_line
			(start 0.120396 0.2794)
			(end -0.12065 0.2794)
			(stroke
				(width 0.1)
				(type default)
			)
			(layer "F.Fab")
		)
		(fp_line
			(start 0.120396 0.3048)
			(end 0.120396 0.2794)
			(stroke
				(width 0.1)
				(type default)
			)
			(layer "F.Fab")
		)
		(fp_line
			(start 0.12065 -0.3048)
			(end 0.67945 -0.3048)
			(stroke
				(width 0.1)
				(type default)
			)
			(layer "F.Fab")
		)
		(fp_line
			(start 0.12065 -0.2794)
			(end 0.12065 -0.3048)
			(stroke
				(width 0.1)
				(type default)
			)
			(layer "F.Fab")
		)
		(fp_line
			(start 0.67945 -0.3048)
			(end 0.67945 0.3048)
			(stroke
				(width 0.1)
				(type default)
			)
			(layer "F.Fab")
		)
		(fp_line
			(start 0.67945 0.3048)
			(end 0.120396 0.3048)
			(stroke
				(width 0.1)
				(type default)
			)
			(layer "F.Fab")
		)
		(pad "1" smd circle
			(at -0.40005 0)
			(size 0 0)
			(layers "F.Cu" "F.Mask" "F.Paste")
			(net "SH_PVCCIN_CPU0_R")
		)
		(pad "2" smd circle
			(at 0.40005 0)
			(size 0 0)
			(layers "F.Cu" "F.Mask" "F.Paste")
			(net "VSENSE_PVCCIN_CPU0_DN")
		)
	)
	(footprint ""
		(layer "F.Cu")
		(at 422.497504 -131.975352 -90)
		(property "Reference" "PC1372"
			(at 0 0 270)
			(layer "F.SilkS")
			(hide yes)
			(effects
				(font
					(size 1.27 1.27)
				)
			)
		)
		(property "Value" ""
			(at 0 0 270)
			(layer "F.Fab")
			(effects
				(font
					(size 1.27 1.27)
				)
			)
		)
		(duplicate_pad_numbers_are_jumpers no)
		(fp_line
			(start -0.7874 0.4064)
			(end -0.7874 -0.4064)
			(stroke
				(width 0.1524)
				(type default)
			)
			(layer "F.SilkS")
		)
		(fp_line
			(start 0.7874 0.4064)
			(end -0.7874 0.4064)
			(stroke
				(width 0.1524)
				(type default)
			)
			(layer "F.SilkS")
		)
		(fp_line
			(start -0.7874 -0.4064)
			(end 0.7874 -0.4064)
			(stroke
				(width 0.1524)
				(type default)
			)
			(layer "F.SilkS")
		)
		(fp_line
			(start 0.7874 -0.4064)
			(end 0.7874 0.4064)
			(stroke
				(width 0.1524)
				(type default)
			)
			(layer "F.SilkS")
		)
		(fp_line
			(start -0.67945 0.3048)
			(end -0.67945 -0.305054)
			(stroke
				(width 0.1)
				(type default)
			)
			(layer "F.Fab")
		)
		(fp_line
			(start -0.12065 0.3048)
			(end -0.67945 0.3048)
			(stroke
				(width 0.1)
				(type default)
			)
			(layer "F.Fab")
		)
		(fp_line
			(start 0.120396 0.3048)
			(end 0.120396 0.2794)
			(stroke
				(width 0.1)
				(type default)
			)
			(layer "F.Fab")
		)
		(fp_line
			(start 0.67945 0.3048)
			(end 0.120396 0.3048)
			(stroke
				(width 0.1)
				(type default)
			)
			(layer "F.Fab")
		)
		(fp_line
			(start -0.12065 0.2794)
			(end -0.12065 0.3048)
			(stroke
				(width 0.1)
				(type default)
			)
			(layer "F.Fab")
		)
		(fp_line
			(start 0.120396 0.2794)
			(end -0.12065 0.2794)
			(stroke
				(width 0.1)
				(type default)
			)
			(layer "F.Fab")
		)
		(fp_line
			(start -0.12065 -0.2794)
			(end 0.12065 -0.2794)
			(stroke
				(width 0.1)
				(type default)
			)
			(layer "F.Fab")
		)
		(fp_line
			(start 0.12065 -0.2794)
			(end 0.12065 -0.3048)
			(stroke
				(width 0.1)
				(type default)
			)
			(layer "F.Fab")
		)
		(fp_line
			(start 0.12065 -0.3048)
			(end 0.67945 -0.3048)
			(stroke
				(width 0.1)
				(type default)
			)
			(layer "F.Fab")
		)
		(fp_line
			(start 0.67945 -0.3048)
			(end 0.67945 0.3048)
			(stroke
				(width 0.1)
				(type default)
			)
			(layer "F.Fab")
		)
		(fp_line
			(start -0.67945 -0.305054)
			(end -0.12065 -0.305054)
			(stroke
				(width 0.1)
				(type default)
			)
			(layer "F.Fab")
		)
		(fp_line
			(start -0.12065 -0.305054)
			(end -0.12065 -0.2794)
			(stroke
				(width 0.1)
				(type default)
			)
			(layer "F.Fab")
		)
		(pad "1" smd circle
			(at -0.40005 0 270)
			(size 0 0)
			(layers "F.Cu" "F.Mask" "F.Paste")
			(net "PVCCINFAON_CPU0_VREF")
		)
		(pad "2" smd circle
			(at 0.40005 0 270)
			(size 0 0)
			(layers "F.Cu" "F.Mask" "F.Paste")
			(net "GND")
		)
	)
	(footprint ""
		(layer "F.Cu")
		(at 337.730084 -27.678126 -90)
		(property "Reference" "R913"
			(at 0 0 270)
			(layer "F.SilkS")
			(hide yes)
			(effects
				(font
					(size 1.27 1.27)
				)
			)
		)
		(property "Value" ""
			(at 0 0 270)
			(layer "F.Fab")
			(effects
				(font
					(size 1.27 1.27)
				)
			)
		)
		(duplicate_pad_numbers_are_jumpers no)
		(fp_line
			(start -0.7874 0.4064)
			(end -0.7874 -0.4064)
			(stroke
				(width 0.1524)
				(type default)
			)
			(layer "F.SilkS")
		)
		(fp_line
			(start 0.7874 0.4064)
			(end -0.7874 0.4064)
			(stroke
				(width 0.1524)
				(type default)
			)
			(layer "F.SilkS")
		)
		(fp_line
			(start -0.7874 -0.4064)
			(end 0.7874 -0.4064)
			(stroke
				(width 0.1524)
				(type default)
			)
			(layer "F.SilkS")
		)
		(fp_line
			(start 0.7874 -0.4064)
			(end 0.7874 0.4064)
			(stroke
				(width 0.1524)
				(type default)
			)
			(layer "F.SilkS")
		)
		(fp_line
			(start -0.67945 0.3048)
			(end -0.67945 -0.305054)
			(stroke
				(width 0.1)
				(type default)
			)
			(layer "F.Fab")
		)
		(fp_line
			(start -0.12065 0.3048)
			(end -0.67945 0.3048)
			(stroke
				(width 0.1)
				(type default)
			)
			(layer "F.Fab")
		)
		(fp_line
			(start 0.120396 0.3048)
			(end 0.120396 0.2794)
			(stroke
				(width 0.1)
				(type default)
			)
			(layer "F.Fab")
		)
		(fp_line
			(start 0.67945 0.3048)
			(end 0.120396 0.3048)
			(stroke
				(width 0.1)
				(type default)
			)
			(layer "F.Fab")
		)
		(fp_line
			(start -0.12065 0.2794)
			(end -0.12065 0.3048)
			(stroke
				(width 0.1)
				(type default)
			)
			(layer "F.Fab")
		)
		(fp_line
			(start 0.120396 0.2794)
			(end -0.12065 0.2794)
			(stroke
				(width 0.1)
				(type default)
			)
			(layer "F.Fab")
		)
		(fp_line
			(start -0.12065 -0.2794)
			(end 0.12065 -0.2794)
			(stroke
				(width 0.1)
				(type default)
			)
			(layer "F.Fab")
		)
		(fp_line
			(start 0.12065 -0.2794)
			(end 0.12065 -0.3048)
			(stroke
				(width 0.1)
				(type default)
			)
			(layer "F.Fab")
		)
		(fp_line
			(start 0.12065 -0.3048)
			(end 0.67945 -0.3048)
			(stroke
				(width 0.1)
				(type default)
			)
			(layer "F.Fab")
		)
		(fp_line
			(start 0.67945 -0.3048)
			(end 0.67945 0.3048)
			(stroke
				(width 0.1)
				(type default)
			)
			(layer "F.Fab")
		)
		(fp_line
			(start -0.67945 -0.305054)
			(end -0.12065 -0.305054)
			(stroke
				(width 0.1)
				(type default)
			)
			(layer "F.Fab")
		)
		(fp_line
			(start -0.12065 -0.305054)
			(end -0.12065 -0.2794)
			(stroke
				(width 0.1)
				(type default)
			)
			(layer "F.Fab")
		)
		(pad "1" smd circle
			(at -0.40005 0 270)
			(size 0 0)
			(layers "F.Cu" "F.Mask" "F.Paste")
			(net "PU_OC6_USB_N")
		)
		(pad "2" smd circle
			(at 0.40005 0 270)
			(size 0 0)
			(layers "F.Cu" "F.Mask" "F.Paste")
			(net "P3V3_AUX")
		)
	)
	(footprint ""
		(layer "F.Cu")
		(at 312.443622 -38.89121 180)
		(property "Reference" "R4100"
			(at 0 0 180)
			(layer "F.SilkS")
			(hide yes)
			(effects
				(font
					(size 1.27 1.27)
				)
			)
		)
		(property "Value" ""
			(at 0 0 180)
			(layer "F.Fab")
			(effects
				(font
					(size 1.27 1.27)
				)
			)
		)
		(duplicate_pad_numbers_are_jumpers no)
		(fp_line
			(start 0.7874 0.4064)
			(end -0.7874 0.4064)
			(stroke
				(width 0.1524)
				(type default)
			)
			(layer "F.SilkS")
		)
		(fp_line
			(start 0.7874 -0.4064)
			(end 0.7874 0.4064)
			(stroke
				(width 0.1524)
				(type default)
			)
			(layer "F.SilkS")
		)
		(fp_line
			(start -0.7874 0.4064)
			(end -0.7874 -0.4064)
			(stroke
				(width 0.1524)
				(type default)
			)
			(layer "F.SilkS")
		)
		(fp_line
			(start -0.7874 -0.4064)
			(end 0.7874 -0.4064)
			(stroke
				(width 0.1524)
				(type default)
			)
			(layer "F.SilkS")
		)
		(fp_line
			(start 0.67945 0.3048)
			(end 0.120396 0.3048)
			(stroke
				(width 0.1)
				(type default)
			)
			(layer "F.Fab")
		)
		(fp_line
			(start 0.67945 -0.3048)
			(end 0.67945 0.3048)
			(stroke
				(width 0.1)
				(type default)
			)
			(layer "F.Fab")
		)
		(fp_line
			(start 0.12065 -0.2794)
			(end 0.12065 -0.3048)
			(stroke
				(width 0.1)
				(type default)
			)
			(layer "F.Fab")
		)
		(fp_line
			(start 0.12065 -0.3048)
			(end 0.67945 -0.3048)
			(stroke
				(width 0.1)
				(type default)
			)
			(layer "F.Fab")
		)
		(fp_line
			(start 0.120396 0.3048)
			(end 0.120396 0.2794)
			(stroke
				(width 0.1)
				(type default)
			)
			(layer "F.Fab")
		)
		(fp_line
			(start 0.120396 0.2794)
			(end -0.12065 0.2794)
			(stroke
				(width 0.1)
				(type default)
			)
			(layer "F.Fab")
		)
		(fp_line
			(start -0.12065 0.3048)
			(end -0.67945 0.3048)
			(stroke
				(width 0.1)
				(type default)
			)
			(layer "F.Fab")
		)
		(fp_line
			(start -0.12065 0.2794)
			(end -0.12065 0.3048)
			(stroke
				(width 0.1)
				(type default)
			)
			(layer "F.Fab")
		)
		(fp_line
			(start -0.12065 -0.2794)
			(end 0.12065 -0.2794)
			(stroke
				(width 0.1)
				(type default)
			)
			(layer "F.Fab")
		)
		(fp_line
			(start -0.12065 -0.305054)
			(end -0.12065 -0.2794)
			(stroke
				(width 0.1)
				(type default)
			)
			(layer "F.Fab")
		)
		(fp_line
			(start -0.67945 0.3048)
			(end -0.67945 -0.305054)
			(stroke
				(width 0.1)
				(type default)
			)
			(layer "F.Fab")
		)
		(fp_line
			(start -0.67945 -0.305054)
			(end -0.12065 -0.305054)
			(stroke
				(width 0.1)
				(type default)
			)
			(layer "F.Fab")
		)
		(pad "1" smd circle
			(at -0.40005 0 180)
			(size 0 0)
			(layers "F.Cu" "F.Mask" "F.Paste")
			(net "PD_PCH_GPPC_C10")
		)
		(pad "2" smd circle
			(at 0.40005 0 180)
			(size 0 0)
			(layers "F.Cu" "F.Mask" "F.Paste")
			(net "GND")
		)
	)
	(footprint ""
		(layer "F.Cu")
		(at 342.43899 -70.03796 90)
		(property "Reference" "C153"
			(at 0 0 90)
			(layer "F.SilkS")
			(hide yes)
			(effects
				(font
					(size 1.27 1.27)
				)
			)
		)
		(property "Value" ""
			(at 0 0 90)
			(layer "F.Fab")
			(effects
				(font
					(size 1.27 1.27)
				)
			)
		)
		(duplicate_pad_numbers_are_jumpers no)
		(fp_line
			(start 0.299974 -0.150114)
			(end 0.299974 0.150114)
			(stroke
				(width 0.1)
				(type default)
			)
			(layer "F.Fab")
		)
		(fp_line
			(start -0.299974 -0.150114)
			(end 0.299974 -0.150114)
			(stroke
				(width 0.1)
				(type default)
			)
			(layer "F.Fab")
		)
		(fp_line
			(start 0.299974 0.150114)
			(end -0.299974 0.150114)
			(stroke
				(width 0.1)
				(type default)
			)
			(layer "F.Fab")
		)
		(fp_line
			(start -0.299974 0.150114)
			(end -0.299974 -0.150114)
			(stroke
				(width 0.1)
				(type default)
			)
			(layer "F.Fab")
		)
		(pad "1" smd rect
			(at -0.2667 0 90)
			(size 0.3048 0.381)
			(layers "F.Cu" "F.Mask" "F.Paste")
			(net "DMI_CPU0_PCH_TX_C_DN<0>")
		)
		(pad "2" smd rect
			(at 0.2667 0 90)
			(size 0.3048 0.381)
			(layers "F.Cu" "F.Mask" "F.Paste")
			(net "DMI_CPU0_PCH_TX_DN<0>")
		)
	)
	(footprint ""
		(layer "F.Cu")
		(at 64.614298 -23.554182)
		(property "Reference" "PR3857"
			(at 0 0 0)
			(layer "F.SilkS")
			(hide yes)
			(effects
				(font
					(size 1.27 1.27)
				)
			)
		)
		(property "Value" ""
			(at 0 0 0)
			(layer "F.Fab")
			(effects
				(font
					(size 1.27 1.27)
				)
			)
		)
		(duplicate_pad_numbers_are_jumpers no)
		(fp_line
			(start -1.2954 -0.5842)
			(end 1.2954 -0.5842)
			(stroke
				(width 0.1524)
				(type default)
			)
			(layer "F.SilkS")
		)
		(fp_line
			(start -1.2954 0.5842)
			(end -1.2954 -0.5842)
			(stroke
				(width 0.1524)
				(type default)
			)
			(layer "F.SilkS")
		)
		(fp_line
			(start 1.2954 -0.5842)
			(end 1.2954 0.5842)
			(stroke
				(width 0.1524)
				(type default)
			)
			(layer "F.SilkS")
		)
		(fp_line
			(start 1.2954 0.5842)
			(end -1.2954 0.5842)
			(stroke
				(width 0.1524)
				(type default)
			)
			(layer "F.SilkS")
		)
		(fp_line
			(start -1.1938 -0.406654)
			(end -0.8636 -0.406654)
			(stroke
				(width 0.1)
				(type default)
			)
			(layer "F.Fab")
		)
		(fp_line
			(start -1.1938 0.4064)
			(end -1.1938 -0.406654)
			(stroke
				(width 0.1)
				(type default)
			)
			(layer "F.Fab")
		)
		(fp_line
			(start -0.8636 -0.4572)
			(end 0.8636 -0.4572)
			(stroke
				(width 0.1)
				(type default)
			)
			(layer "F.Fab")
		)
		(fp_line
			(start -0.8636 -0.406654)
			(end -0.8636 -0.4572)
			(stroke
				(width 0.1)
				(type default)
			)
			(layer "F.Fab")
		)
		(fp_line
			(start -0.8636 0.4064)
			(end -1.1938 0.4064)
			(stroke
				(width 0.1)
				(type default)
			)
			(layer "F.Fab")
		)
		(fp_line
			(start -0.8636 0.4318)
			(end -0.8636 0.4064)
			(stroke
				(width 0.1)
				(type default)
			)
			(layer "F.Fab")
		)
		(fp_line
			(start -0.8636 0.4572)
			(end -0.8636 0.4318)
			(stroke
				(width 0.1)
				(type default)
			)
			(layer "F.Fab")
		)
		(fp_line
			(start 0.8636 -0.4572)
			(end 0.8636 -0.406654)
			(stroke
				(width 0.1)
				(type default)
			)
			(layer "F.Fab")
		)
		(fp_line
			(start 0.8636 -0.406654)
			(end 1.1938 -0.406654)
			(stroke
				(width 0.1)
				(type default)
			)
			(layer "F.Fab")
		)
		(fp_line
			(start 0.8636 0.4064)
			(end 0.8636 0.4572)
			(stroke
				(width 0.1)
				(type default)
			)
			(layer "F.Fab")
		)
		(fp_line
			(start 0.8636 0.4572)
			(end -0.8636 0.4572)
			(stroke
				(width 0.1)
				(type default)
			)
			(layer "F.Fab")
		)
		(fp_line
			(start 1.1938 -0.406654)
			(end 1.1938 0.4064)
			(stroke
				(width 0.1)
				(type default)
			)
			(layer "F.Fab")
		)
		(fp_line
			(start 1.1938 0.4064)
			(end 0.8636 0.4064)
			(stroke
				(width 0.1)
				(type default)
			)
			(layer "F.Fab")
		)
		(pad "1" smd rect
			(at -0.7366 0 270)
			(size 0.7112 0.8128)
			(layers "F.Cu" "F.Mask" "F.Paste")
			(net "P12V_AUX")
		)
		(pad "2" smd rect
			(at 0.7366 0 270)
			(size 0.7112 0.8128)
			(layers "F.Cu" "F.Mask" "F.Paste")
			(net "P12V_OCP_AVIN_PD_2")
		)
	)
	(footprint ""
		(layer "F.Cu")
		(at 362.546646 -365.287814 90)
		(property "Reference" "PC335"
			(at 0 0 90)
			(layer "F.SilkS")
			(hide yes)
			(effects
				(font
					(size 1.27 1.27)
				)
			)
		)
		(property "Value" ""
			(at 0 0 90)
			(layer "F.Fab")
			(effects
				(font
					(size 1.27 1.27)
				)
			)
		)
		(duplicate_pad_numbers_are_jumpers no)
		(fp_line
			(start 0.7874 -0.4064)
			(end 0.7874 0.4064)
			(stroke
				(width 0.1524)
				(type default)
			)
			(layer "F.SilkS")
		)
		(fp_line
			(start -0.7874 -0.4064)
			(end 0.7874 -0.4064)
			(stroke
				(width 0.1524)
				(type default)
			)
			(layer "F.SilkS")
		)
		(fp_line
			(start 0.7874 0.4064)
			(end -0.7874 0.4064)
			(stroke
				(width 0.1524)
				(type default)
			)
			(layer "F.SilkS")
		)
		(fp_line
			(start -0.7874 0.4064)
			(end -0.7874 -0.4064)
			(stroke
				(width 0.1524)
				(type default)
			)
			(layer "F.SilkS")
		)
		(fp_line
			(start -0.12065 -0.305054)
			(end -0.12065 -0.2794)
			(stroke
				(width 0.1)
				(type default)
			)
			(layer "F.Fab")
		)
		(fp_line
			(start -0.67945 -0.305054)
			(end -0.12065 -0.305054)
			(stroke
				(width 0.1)
				(type default)
			)
			(layer "F.Fab")
		)
		(fp_line
			(start 0.67945 -0.3048)
			(end 0.67945 0.3048)
			(stroke
				(width 0.1)
				(type default)
			)
			(layer "F.Fab")
		)
		(fp_line
			(start 0.12065 -0.3048)
			(end 0.67945 -0.3048)
			(stroke
				(width 0.1)
				(type default)
			)
			(layer "F.Fab")
		)
		(fp_line
			(start 0.12065 -0.2794)
			(end 0.12065 -0.3048)
			(stroke
				(width 0.1)
				(type default)
			)
			(layer "F.Fab")
		)
		(fp_line
			(start -0.12065 -0.2794)
			(end 0.12065 -0.2794)
			(stroke
				(width 0.1)
				(type default)
			)
			(layer "F.Fab")
		)
		(fp_line
			(start 0.120396 0.2794)
			(end -0.12065 0.2794)
			(stroke
				(width 0.1)
				(type default)
			)
			(layer "F.Fab")
		)
		(fp_line
			(start -0.12065 0.2794)
			(end -0.12065 0.3048)
			(stroke
				(width 0.1)
				(type default)
			)
			(layer "F.Fab")
		)
		(fp_line
			(start 0.67945 0.3048)
			(end 0.120396 0.3048)
			(stroke
				(width 0.1)
				(type default)
			)
			(layer "F.Fab")
		)
		(fp_line
			(start 0.120396 0.3048)
			(end 0.120396 0.2794)
			(stroke
				(width 0.1)
				(type default)
			)
			(layer "F.Fab")
		)
		(fp_line
			(start -0.12065 0.3048)
			(end -0.67945 0.3048)
			(stroke
				(width 0.1)
				(type default)
			)
			(layer "F.Fab")
		)
		(fp_line
			(start -0.67945 0.3048)
			(end -0.67945 -0.305054)
			(stroke
				(width 0.1)
				(type default)
			)
			(layer "F.Fab")
		)
		(pad "1" smd circle
			(at -0.40005 0 90)
			(size 0 0)
			(layers "F.Cu" "F.Mask" "F.Paste")
			(net "PVCCIN_CPU0_VREF")
		)
		(pad "2" smd circle
			(at 0.40005 0 90)
			(size 0 0)
			(layers "F.Cu" "F.Mask" "F.Paste")
			(net "GND")
		)
	)
)
